FILE_TYPE=LIBRARY_PARTS;
primitive 'TDR_3P','TDR_3P_TH','TDR_3P_TH1';
  pin
    'IO1':
      PIN_NUMBER='(1)';
      PINUSE='UNSPEC';
      NO_LOAD_CHECK='BOTH';
      NO_IO_CHECK='BOTH';
      ALLOW_CONNECT='TRUE';
    'IO2':
      PIN_NUMBER='(2)';
      PINUSE='UNSPEC';
      NO_LOAD_CHECK='BOTH';
      NO_IO_CHECK='BOTH';
      ALLOW_CONNECT='TRUE';
    'IO3':
      PIN_NUMBER='(3)';
      PINUSE='UNSPEC';
      NO_LOAD_CHECK='BOTH';
      NO_IO_CHECK='BOTH';
      ALLOW_CONNECT='TRUE';
  end_pin;
  body
    PART_NAME='TDR_3P';
    BODY_NAME='TDR_3P';
    PHYS_DES_PREFIX='DB';
    CLASS='IO';
  end_body;
end_primitive;

primitive 'TDR_3P_TH2';
  pin
    'GND':
      PIN_NUMBER='(1)';
      PINUSE='UNSPEC';
      NO_LOAD_CHECK='BOTH';
      NO_IO_CHECK='BOTH';
      ALLOW_CONNECT='TRUE';
    'IO1':
      PIN_NUMBER='(2)';
      PINUSE='UNSPEC';
      NO_LOAD_CHECK='BOTH';
      NO_IO_CHECK='BOTH';
      ALLOW_CONNECT='TRUE';
    'IO2':
      PIN_NUMBER='(3)';
      PINUSE='UNSPEC';
      NO_LOAD_CHECK='BOTH';
      NO_IO_CHECK='BOTH';
      ALLOW_CONNECT='TRUE';
  end_pin;
  body
    PART_NAME='TDR_3P';
    BODY_NAME='TDR_3P';
    PHYS_DES_PREFIX='DB';
    CLASS='IO';
  end_body;
end_primitive;

END.
